(kicad_pcb
	(version 20241229)
	(generator "pcbnew")
	(generator_version "9.0")
	(general
		(thickness 1.6)
		(legacy_teardrops no)
	)
	(paper "A4")
	(title_block
		(title "environment-sensor")
		(comment 1 "footprints 67-73 of 109")
	)
	(layers
		(0 "F.Cu" signal)
		(4 "In1.Cu" signal)
		(6 "In2.Cu" signal)
		(2 "B.Cu" signal)
		(9 "F.Adhes" user "F.Adhesive")
		(11 "B.Adhes" user "B.Adhesive")
		(13 "F.Paste" user)
		(15 "B.Paste" user)
		(5 "F.SilkS" user "F.Silkscreen")
		(7 "B.SilkS" user "B.Silkscreen")
		(1 "F.Mask" user)
		(3 "B.Mask" user)
		(17 "Dwgs.User" user "User.Drawings")
		(19 "Cmts.User" user "User.Comments")
		(21 "Eco1.User" user "User.Eco1")
		(23 "Eco2.User" user "User.Eco2")
		(25 "Edge.Cuts" user)
		(27 "Margin" user)
		(31 "F.CrtYd" user "F.Courtyard")
		(29 "B.CrtYd" user "B.Courtyard")
		(35 "F.Fab" user)
		(33 "B.Fab" user)
	)
	(footprint "antmicro-footprints:R_0402_1005Metric"
		(layer "F.Cu")
		(at 169.985 123.7)
		(descr "Resistor SMD 0402")
		(tags "resistor SMD 0402")
		(property "Reference" "R3"
			(at 0.865 0.35 0)
			(layer "F.SilkS")
			(effects
				(font
					(size 0.7 0.7)
					(thickness 0.15)
				)
				(justify left bottom)
			)
		)
		(property "Value" "R_5k1_0402"
			(at 0 1.4 0)
			(layer "F.Fab")
			(effects
				(font
					(size 0.7 0.7)
					(thickness 0.15)
				)
				(justify left bottom)
			)
		)
		(property "Description" "SMD Chip Resistor, 5.1 kohm, ± 1%, 63 mW, 0402 [1005 Metric], Thick Film, General Purpose"
			(at 0 0 0)
			(layer "F.Fab")
			(hide yes)
			(effects
				(font
					(size 1.27 1.27)
					(thickness 0.15)
				)
			)
		)
		(property "Author" "Antmicro"
			(at 0 0 0)
			(layer "F.Fab")
			(hide yes)
			(effects
				(font
					(size 1 1)
					(thickness 0.15)
				)
			)
		)
		(property "License" "Apache-2.0"
			(at 0 0 0)
			(layer "F.Fab")
			(hide yes)
			(effects
				(font
					(size 1 1)
					(thickness 0.15)
				)
			)
		)
		(property "MPN" "CR0402-FX-5101GLF"
			(at 0 0 0)
			(layer "F.Fab")
			(hide yes)
			(effects
				(font
					(size 1 1)
					(thickness 0.15)
				)
			)
		)
		(property "Manufacturer" "Bourns"
			(at 0 0 0)
			(layer "F.Fab")
			(hide yes)
			(effects
				(font
					(size 1 1)
					(thickness 0.15)
				)
			)
		)
		(property "Public" "False"
			(at 0 0 0)
			(layer "F.Fab")
			(hide yes)
			(effects
				(font
					(size 1 1)
					(thickness 0.15)
				)
			)
		)
		(property "Tolerance" "1%"
			(at 0 0 0)
			(layer "F.Fab")
			(hide yes)
			(effects
				(font
					(size 1 1)
					(thickness 0.15)
				)
			)
		)
		(property "Val" "5k1"
			(at 0 0 0)
			(layer "F.Fab")
			(hide yes)
			(effects
				(font
					(size 1 1)
					(thickness 0.15)
				)
			)
		)
		(sheetfile "environment-sensor.kicad_sch")
		(attr smd)
		(fp_rect
			(start -0.925 -0.47)
			(end 0.925 0.47)
			(stroke
				(width 0.05)
				(type default)
			)
			(fill no)
			(layer "F.CrtYd")
		)
		(fp_rect
			(start -0.5 -0.25)
			(end 0.5 0.25)
			(stroke
				(width 0.15)
				(type solid)
			)
			(fill no)
			(layer "F.Fab")
		)
		(pad "1" smd roundrect
			(at -0.48 0)
			(size 0.59 0.64)
			(layers "F.Cu" "F.Mask" "F.Paste")
			(roundrect_rratio 0.25)
			(net 1 "GND")
			(pintype "passive")
		)
		(pad "2" smd roundrect
			(at 0.48 0)
			(size 0.59 0.64)
			(layers "F.Cu" "F.Mask" "F.Paste")
			(roundrect_rratio 0.25)
			(net 4 "/USB_CC1")
			(pintype "passive")
		)
	)
	(footprint "antmicro-footprints:R_0402_1005Metric"
		(layer "F.Cu")
		(at 182.5 138.4 90)
		(descr "Resistor SMD 0402")
		(tags "resistor SMD 0402")
		(property "Reference" "R19"
			(at 20.346 -0.4185 90)
			(layer "B.SilkS")
			(effects
				(font
					(size 0.7 0.7)
					(thickness 0.15)
				)
				(justify left bottom mirror)
			)
		)
		(property "Value" "R_100k_0402"
			(at 0 1.4 90)
			(layer "F.Fab")
			(effects
				(font
					(size 0.7 0.7)
					(thickness 0.15)
				)
				(justify left bottom)
			)
		)
		(property "Description" "SMD Chip Resistor, 100 kohm, ± 1%, 62.5 mW, 0402 [1005 Metric], Thick Film, General Purpose"
			(at 0 0 90)
			(layer "F.Fab")
			(hide yes)
			(effects
				(font
					(size 1.27 1.27)
					(thickness 0.15)
				)
			)
		)
		(property "Author" "Antmicro"
			(at 320.9 -44.1 0)
			(layer "F.Fab")
			(hide yes)
			(effects
				(font
					(size 1 1)
					(thickness 0.15)
				)
			)
		)
		(property "License" "Apache-2.0"
			(at 320.9 -44.1 0)
			(layer "F.Fab")
			(hide yes)
			(effects
				(font
					(size 1 1)
					(thickness 0.15)
				)
			)
		)
		(property "MPN" "CR0402-FX-1003GLF"
			(at 320.9 -44.1 0)
			(layer "F.Fab")
			(hide yes)
			(effects
				(font
					(size 1 1)
					(thickness 0.15)
				)
			)
		)
		(property "Manufacturer" "Bourns"
			(at 320.9 -44.1 0)
			(layer "F.Fab")
			(hide yes)
			(effects
				(font
					(size 1 1)
					(thickness 0.15)
				)
			)
		)
		(property "Public" "False"
			(at 320.9 -44.1 0)
			(layer "F.Fab")
			(hide yes)
			(effects
				(font
					(size 1 1)
					(thickness 0.15)
				)
			)
		)
		(property "Tolerance" "1%"
			(at 320.9 -44.1 0)
			(layer "F.Fab")
			(hide yes)
			(effects
				(font
					(size 1 1)
					(thickness 0.15)
				)
			)
		)
		(property "Val" "100k"
			(at 320.9 -44.1 0)
			(layer "F.Fab")
			(hide yes)
			(effects
				(font
					(size 1 1)
					(thickness 0.15)
				)
			)
		)
		(sheetfile "environment-sensor.kicad_sch")
		(attr smd)
		(fp_rect
			(start -0.925 -0.47)
			(end 0.925 0.47)
			(stroke
				(width 0.05)
				(type default)
			)
			(fill no)
			(layer "F.CrtYd")
		)
		(fp_rect
			(start -0.5 -0.25)
			(end 0.5 0.25)
			(stroke
				(width 0.15)
				(type solid)
			)
			(fill no)
			(layer "F.Fab")
		)
		(pad "1" smd roundrect
			(at -0.48 0 90)
			(size 0.59 0.64)
			(layers "F.Cu" "F.Mask" "F.Paste")
			(roundrect_rratio 0.25)
			(net 14 "NRST")
			(pintype "passive")
		)
		(pad "2" smd roundrect
			(at 0.48 0 90)
			(size 0.59 0.64)
			(layers "F.Cu" "F.Mask" "F.Paste")
			(roundrect_rratio 0.25)
			(net 2 "+3V3")
			(pintype "passive")
		)
	)
	(footprint "antmicro-footprints:R_0402_1005Metric"
		(layer "F.Cu")
		(at 182.729 120.6235)
		(descr "Resistor SMD 0402")
		(tags "resistor SMD 0402")
		(property "Reference" "R34"
			(at -3.129 0.3765 180)
			(layer "F.SilkS")
			(effects
				(font
					(size 0.7 0.7)
					(thickness 0.15)
				)
				(justify left bottom)
			)
		)
		(property "Value" "R_100k_0402"
			(at 0 1.4 0)
			(layer "F.Fab")
			(effects
				(font
					(size 0.7 0.7)
					(thickness 0.15)
				)
				(justify left bottom)
			)
		)
		(property "Description" "SMD Chip Resistor, 100 kohm, ± 1%, 62.5 mW, 0402 [1005 Metric], Thick Film, General Purpose"
			(at 0 0 0)
			(layer "F.Fab")
			(hide yes)
			(effects
				(font
					(size 1.27 1.27)
					(thickness 0.15)
				)
			)
		)
		(property "Author" "Antmicro"
			(at 0 0 0)
			(layer "F.Fab")
			(hide yes)
			(effects
				(font
					(size 1 1)
					(thickness 0.15)
				)
			)
		)
		(property "License" "Apache-2.0"
			(at 0 0 0)
			(layer "F.Fab")
			(hide yes)
			(effects
				(font
					(size 1 1)
					(thickness 0.15)
				)
			)
		)
		(property "MPN" "CR0402-FX-1003GLF"
			(at 0 0 0)
			(layer "F.Fab")
			(hide yes)
			(effects
				(font
					(size 1 1)
					(thickness 0.15)
				)
			)
		)
		(property "Manufacturer" "Bourns"
			(at 0 0 0)
			(layer "F.Fab")
			(hide yes)
			(effects
				(font
					(size 1 1)
					(thickness 0.15)
				)
			)
		)
		(property "Public" "False"
			(at 0 0 0)
			(layer "F.Fab")
			(hide yes)
			(effects
				(font
					(size 1 1)
					(thickness 0.15)
				)
			)
		)
		(property "Tolerance" "1%"
			(at 0 0 0)
			(layer "F.Fab")
			(hide yes)
			(effects
				(font
					(size 1 1)
					(thickness 0.15)
				)
			)
		)
		(property "Val" "100k"
			(at 0 0 0)
			(layer "F.Fab")
			(hide yes)
			(effects
				(font
					(size 1 1)
					(thickness 0.15)
				)
			)
		)
		(sheetfile "environment-sensor.kicad_sch")
		(attr smd)
		(fp_rect
			(start -0.925 -0.47)
			(end 0.925 0.47)
			(stroke
				(width 0.05)
				(type default)
			)
			(fill no)
			(layer "F.CrtYd")
		)
		(fp_rect
			(start -0.5 -0.25)
			(end 0.5 0.25)
			(stroke
				(width 0.15)
				(type solid)
			)
			(fill no)
			(layer "F.Fab")
		)
		(pad "1" smd roundrect
			(at -0.48 0)
			(size 0.59 0.64)
			(layers "F.Cu" "F.Mask" "F.Paste")
			(roundrect_rratio 0.25)
			(net 1 "GND")
			(pintype "passive")
		)
		(pad "2" smd roundrect
			(at 0.48 0)
			(size 0.59 0.64)
			(layers "F.Cu" "F.Mask" "F.Paste")
			(roundrect_rratio 0.25)
			(net 52 "Net-(U4-A2)")
			(pintype "passive")
		)
	)
	(footprint "antmicro-footprints:R_0402_1005Metric"
		(layer "F.Cu")
		(at 181.744 126.25 90)
		(descr "Resistor SMD 0402")
		(tags "resistor SMD 0402")
		(property "Reference" "R10"
			(at 11.75 1.156 90)
			(layer "B.SilkS")
			(effects
				(font
					(size 0.7 0.7)
					(thickness 0.15)
				)
				(justify left bottom mirror)
			)
		)
		(property "Value" "R_0R_0402"
			(at 0 1.4 90)
			(layer "F.Fab")
			(effects
				(font
					(size 0.7 0.7)
					(thickness 0.15)
				)
				(justify left bottom)
			)
		)
		(property "Description" "SMD Chip Resistor, Jumper, 0 ohm, 100 mW, 0402 [1005 Metric], Thick Film, General Purpose"
			(at 0 0 90)
			(layer "F.Fab")
			(hide yes)
			(effects
				(font
					(size 1.27 1.27)
					(thickness 0.15)
				)
			)
		)
		(property "Author" "Antmicro"
			(at 307.994 -55.494 0)
			(layer "F.Fab")
			(hide yes)
			(effects
				(font
					(size 1 1)
					(thickness 0.15)
				)
			)
		)
		(property "Current" "1A"
			(at 307.994 -55.494 0)
			(layer "F.Fab")
			(hide yes)
			(effects
				(font
					(size 1 1)
					(thickness 0.15)
				)
			)
		)
		(property "License" "Apache-2.0"
			(at 307.994 -55.494 0)
			(layer "F.Fab")
			(hide yes)
			(effects
				(font
					(size 1 1)
					(thickness 0.15)
				)
			)
		)
		(property "MPN" "ERJ2GE0R00X"
			(at 307.994 -55.494 0)
			(layer "F.Fab")
			(hide yes)
			(effects
				(font
					(size 1 1)
					(thickness 0.15)
				)
			)
		)
		(property "Manufacturer" "Panasonic"
			(at 307.994 -55.494 0)
			(layer "F.Fab")
			(hide yes)
			(effects
				(font
					(size 1 1)
					(thickness 0.15)
				)
			)
		)
		(property "Public" "False"
			(at 307.994 -55.494 0)
			(layer "F.Fab")
			(hide yes)
			(effects
				(font
					(size 1 1)
					(thickness 0.15)
				)
			)
		)
		(property "Tolerance" ""
			(at 307.994 -55.494 0)
			(layer "F.Fab")
			(hide yes)
			(effects
				(font
					(size 1 1)
					(thickness 0.15)
				)
			)
		)
		(property "Val" "0R"
			(at 307.994 -55.494 0)
			(layer "F.Fab")
			(hide yes)
			(effects
				(font
					(size 1 1)
					(thickness 0.15)
				)
			)
		)
		(sheetfile "environment-sensor.kicad_sch")
		(attr smd)
		(fp_rect
			(start -0.925 -0.47)
			(end 0.925 0.47)
			(stroke
				(width 0.05)
				(type default)
			)
			(fill no)
			(layer "F.CrtYd")
		)
		(fp_rect
			(start -0.5 -0.25)
			(end 0.5 0.25)
			(stroke
				(width 0.15)
				(type solid)
			)
			(fill no)
			(layer "F.Fab")
		)
		(pad "1" smd roundrect
			(at -0.48 0 90)
			(size 0.59 0.64)
			(layers "F.Cu" "F.Mask" "F.Paste")
			(roundrect_rratio 0.25)
			(net 42 "Net-(U1-RI#)")
			(pintype "passive")
		)
		(pad "2" smd roundrect
			(at 0.48 0 90)
			(size 0.59 0.64)
			(layers "F.Cu" "F.Mask" "F.Paste")
			(roundrect_rratio 0.25)
			(net 25 "JTDI")
			(pintype "passive")
		)
	)
	(footprint "antmicro-footprints:R_0402_1005Metric"
		(layer "F.Cu")
		(at 198.5 130.3 180)
		(descr "Resistor SMD 0402")
		(tags "resistor SMD 0402")
		(property "Reference" "R37"
			(at -0.85 -0.5 180)
			(layer "F.SilkS")
			(effects
				(font
					(size 0.7 0.7)
					(thickness 0.15)
				)
				(justify left bottom)
			)
		)
		(property "Value" "R_5k1_0402"
			(at 0 1.4 180)
			(layer "F.Fab")
			(effects
				(font
					(size 0.7 0.7)
					(thickness 0.15)
				)
				(justify left bottom)
			)
		)
		(property "Description" "SMD Chip Resistor, 5.1 kohm, ± 1%, 63 mW, 0402 [1005 Metric], Thick Film, General Purpose"
			(at 0 0 180)
			(layer "F.Fab")
			(hide yes)
			(effects
				(font
					(size 1.27 1.27)
					(thickness 0.15)
				)
			)
		)
		(property "Author" "Antmicro"
			(at 397 260.6 0)
			(layer "F.Fab")
			(hide yes)
			(effects
				(font
					(size 1 1)
					(thickness 0.15)
				)
			)
		)
		(property "License" "Apache-2.0"
			(at 397 260.6 0)
			(layer "F.Fab")
			(hide yes)
			(effects
				(font
					(size 1 1)
					(thickness 0.15)
				)
			)
		)
		(property "MPN" "CR0402-FX-5101GLF"
			(at 397 260.6 0)
			(layer "F.Fab")
			(hide yes)
			(effects
				(font
					(size 1 1)
					(thickness 0.15)
				)
			)
		)
		(property "Manufacturer" "Bourns"
			(at 397 260.6 0)
			(layer "F.Fab")
			(hide yes)
			(effects
				(font
					(size 1 1)
					(thickness 0.15)
				)
			)
		)
		(property "Public" "False"
			(at 397 260.6 0)
			(layer "F.Fab")
			(hide yes)
			(effects
				(font
					(size 1 1)
					(thickness 0.15)
				)
			)
		)
		(property "Tolerance" "1%"
			(at 397 260.6 0)
			(layer "F.Fab")
			(hide yes)
			(effects
				(font
					(size 1 1)
					(thickness 0.15)
				)
			)
		)
		(property "Val" "5k1"
			(at 397 260.6 0)
			(layer "F.Fab")
			(hide yes)
			(effects
				(font
					(size 1 1)
					(thickness 0.15)
				)
			)
		)
		(sheetfile "environment-sensor.kicad_sch")
		(attr smd)
		(fp_rect
			(start -0.925 -0.47)
			(end 0.925 0.47)
			(stroke
				(width 0.05)
				(type default)
			)
			(fill no)
			(layer "F.CrtYd")
		)
		(fp_rect
			(start -0.5 -0.25)
			(end 0.5 0.25)
			(stroke
				(width 0.15)
				(type solid)
			)
			(fill no)
			(layer "F.Fab")
		)
		(pad "1" smd roundrect
			(at -0.48 0 180)
			(size 0.59 0.64)
			(layers "F.Cu" "F.Mask" "F.Paste")
			(roundrect_rratio 0.25)
			(net 8 "I2C_1_SCL")
			(pintype "passive")
		)
		(pad "2" smd roundrect
			(at 0.48 0 180)
			(size 0.59 0.64)
			(layers "F.Cu" "F.Mask" "F.Paste")
			(roundrect_rratio 0.25)
			(net 2 "+3V3")
			(pintype "passive")
		)
	)
	(footprint "antmicro-footprints:SOD-923"
		(layer "F.Cu")
		(at 202.5 115.6 -90)
		(property "Reference" "D9"
			(at -1.3 0 90)
			(unlocked yes)
			(layer "F.SilkS")
			(effects
				(font
					(size 0.65 0.65)
					(thickness 0.15)
				)
			)
		)
		(property "Value" "ESD9X5.0ST5G"
			(at 0 2.4 270)
			(unlocked yes)
			(layer "F.Fab")
			(effects
				(font
					(size 1 1)
					(thickness 0.15)
				)
			)
		)
		(property "Description" "Unidirectional TVS, 30 kV,  SOD-923, 5 V, 65 pF"
			(at 0 0 270)
			(layer "F.Fab")
			(hide yes)
			(effects
				(font
					(size 1.27 1.27)
					(thickness 0.15)
				)
			)
		)
		(property "Author" "Antmicro"
			(at 86.9 318.1 0)
			(layer "F.Fab")
			(hide yes)
			(effects
				(font
					(size 1 1)
					(thickness 0.15)
				)
			)
		)
		(property "License" "Apache-2.0"
			(at 86.9 318.1 0)
			(layer "F.Fab")
			(hide yes)
			(effects
				(font
					(size 1 1)
					(thickness 0.15)
				)
			)
		)
		(property "MPN" "ESD9X5.0ST5G"
			(at 86.9 318.1 0)
			(layer "F.Fab")
			(hide yes)
			(effects
				(font
					(size 1 1)
					(thickness 0.15)
				)
			)
		)
		(property "Manufacturer" "ON Semiconductor"
			(at 86.9 318.1 0)
			(layer "F.Fab")
			(hide yes)
			(effects
				(font
					(size 1 1)
					(thickness 0.15)
				)
			)
		)
		(property "Public" "False"
			(at 86.9 318.1 0)
			(layer "F.Fab")
			(hide yes)
			(effects
				(font
					(size 1 1)
					(thickness 0.15)
				)
			)
		)
		(sheetfile "environment-sensor.kicad_sch")
		(attr smd)
		(fp_line
			(start -0.5 0.4)
			(end 0.5 0.4)
			(stroke
				(width 0.15)
				(type solid)
			)
			(layer "F.SilkS")
		)
		(fp_line
			(start -0.5 0.4)
			(end -0.5 0.3)
			(stroke
				(width 0.15)
				(type solid)
			)
			(layer "F.SilkS")
		)
		(fp_line
			(start 0.5 0.4)
			(end 0.5 0.3)
			(stroke
				(width 0.15)
				(type solid)
			)
			(layer "F.SilkS")
		)
		(fp_line
			(start -0.5 -0.3)
			(end -0.5 -0.4)
			(stroke
				(width 0.15)
				(type solid)
			)
			(layer "F.SilkS")
		)
		(fp_line
			(start -0.5 -0.4)
			(end 0.5 -0.4)
			(stroke
				(width 0.15)
				(type solid)
			)
			(layer "F.SilkS")
		)
		(fp_line
			(start -0.16 -0.4)
			(end -0.16 0.4)
			(stroke
				(width 0.15)
				(type solid)
			)
			(layer "F.SilkS")
		)
		(fp_line
			(start 0.5 -0.4)
			(end 0.5 -0.3)
			(stroke
				(width 0.15)
				(type solid)
			)
			(layer "F.SilkS")
		)
		(fp_rect
			(start -0.68 -0.41)
			(end 0.68 0.41)
			(stroke
				(width 0.05)
				(type solid)
			)
			(fill no)
			(layer "F.CrtYd")
		)
		(fp_line
			(start -0.202 -0.3)
			(end -0.202 0.298)
			(stroke
				(width 0.15)
				(type solid)
			)
			(layer "F.Fab")
		)
		(fp_rect
			(start -0.402 -0.3)
			(end 0.4 0.298)
			(stroke
				(width 0.15)
				(type solid)
			)
			(fill no)
			(layer "F.Fab")
		)
		(fp_text user "${REFERENCE}"
			(at 0 1.1 270)
			(unlocked yes)
			(layer "F.Fab")
			(effects
				(font
					(size 1 1)
					(thickness 0.15)
				)
			)
		)
		(pad "1" smd roundrect
			(at -0.438 0 270)
			(size 0.4 0.325)
			(layers "F.Cu" "F.Mask" "F.Paste")
			(roundrect_rratio 0.25)
			(net 1 "GND")
			(pinfunction "C")
			(pintype "passive")
		)
		(pad "2" smd roundrect
			(at 0.436 0 270)
			(size 0.4 0.325)
			(layers "F.Cu" "F.Mask" "F.Paste")
			(roundrect_rratio 0.25)
			(net 2 "+3V3")
			(pinfunction "A")
			(pintype "passive")
		)
	)
	(footprint "antmicro-footprints:R_0402_1005Metric"
		(layer "F.Cu")
		(at 179.75 126.25 -90)
		(descr "Resistor SMD 0402")
		(tags "resistor SMD 0402")
		(property "Reference" "R24"
			(at -9.6 -1.35 90)
			(layer "B.SilkS")
			(effects
				(font
					(size 0.7 0.7)
					(thickness 0.15)
				)
				(justify right bottom mirror)
			)
		)
		(property "Value" "R_100k_0402"
			(at 0 1.4 90)
			(layer "F.Fab")
			(effects
				(font
					(size 0.7 0.7)
					(thickness 0.15)
				)
				(justify right bottom)
			)
		)
		(property "Description" "SMD Chip Resistor, 100 kohm, ± 1%, 62.5 mW, 0402 [1005 Metric], Thick Film, General Purpose"
			(at 0 0 270)
			(layer "F.Fab")
			(hide yes)
			(effects
				(font
					(size 1.27 1.27)
					(thickness 0.15)
				)
			)
		)
		(property "Author" "Antmicro"
			(at 53.5 306 0)
			(layer "F.Fab")
			(hide yes)
			(effects
				(font
					(size 1 1)
					(thickness 0.15)
				)
			)
		)
		(property "License" "Apache-2.0"
			(at 53.5 306 0)
			(layer "F.Fab")
			(hide yes)
			(effects
				(font
					(size 1 1)
					(thickness 0.15)
				)
			)
		)
		(property "MPN" "CR0402-FX-1003GLF"
			(at 53.5 306 0)
			(layer "F.Fab")
			(hide yes)
			(effects
				(font
					(size 1 1)
					(thickness 0.15)
				)
			)
		)
		(property "Manufacturer" "Bourns"
			(at 53.5 306 0)
			(layer "F.Fab")
			(hide yes)
			(effects
				(font
					(size 1 1)
					(thickness 0.15)
				)
			)
		)
		(property "Public" "False"
			(at 53.5 306 0)
			(layer "F.Fab")
			(hide yes)
			(effects
				(font
					(size 1 1)
					(thickness 0.15)
				)
			)
		)
		(property "Tolerance" "1%"
			(at 53.5 306 0)
			(layer "F.Fab")
			(hide yes)
			(effects
				(font
					(size 1 1)
					(thickness 0.15)
				)
			)
		)
		(property "Val" "100k"
			(at 53.5 306 0)
			(layer "F.Fab")
			(hide yes)
			(effects
				(font
					(size 1 1)
					(thickness 0.15)
				)
			)
		)
		(sheetfile "environment-sensor.kicad_sch")
		(attr smd)
		(fp_rect
			(start -0.925 -0.47)
			(end 0.925 0.47)
			(stroke
				(width 0.05)
				(type default)
			)
			(fill no)
			(layer "F.CrtYd")
		)
		(fp_rect
			(start -0.5 -0.25)
			(end 0.5 0.25)
			(stroke
				(width 0.15)
				(type solid)
			)
			(fill no)
			(layer "F.Fab")
		)
		(pad "1" smd roundrect
			(at -0.48 0 270)
			(size 0.59 0.64)
			(layers "F.Cu" "F.Mask" "F.Paste")
			(roundrect_rratio 0.25)
			(net 13 "JTRST")
			(pintype "passive")
		)
		(pad "2" smd roundrect
			(at 0.48 0 270)
			(size 0.59 0.64)
			(layers "F.Cu" "F.Mask" "F.Paste")
			(roundrect_rratio 0.25)
			(net 2 "+3V3")
			(pintype "passive")
		)
	)
)
